(kicad_sch
	(version 20250114)
	(generator "eeschema")
	(generator_version "9.0")
	(paper "A3")
	(title_block
		(title "COM Express 7 Baseboard")
		(date "2025-02-04")
		(rev "1.1.2")
		(company "Antmicro Ltd")
		(comment 1 "www.antmicro.com")
	)
	(text "GPIO expander"
		(exclude_from_sim no)
		(at 193.04 112.014 0)
		(effects
			(font
				(size 2 2)
				(thickness 0.8)
				(bold yes)
			)
			(justify left bottom)
		)
	)
	(text "Address 0x74\n"
		(exclude_from_sim no)
		(at 212.09 177.8 0)
		(effects
			(font
				(size 1.27 1.27)
			)
			(justify left bottom)
		)
	)
	(junction
		(at 180.34 121.92)
		(diameter 0)
		(color 0 0 0 0)
	)
	(junction
		(at 180.34 167.64)
		(diameter 0)
		(color 0 0 0 0)
	)
	(junction
		(at 189.23 121.92)
		(diameter 0)
		(color 0 0 0 0)
	)
	(no_connect
		(at 223.52 160.02)
	)
	(no_connect
		(at 223.52 162.56)
	)
	(no_connect
		(at 223.52 170.18)
	)
	(no_connect
		(at 223.52 167.64)
	)
	(no_connect
		(at 223.52 157.48)
	)
	(no_connect
		(at 223.52 172.72)
	)
	(no_connect
		(at 223.52 154.94)
	)
	(no_connect
		(at 223.52 165.1)
	)
	(bus_entry
		(at 163.83 139.7)
		(size -1.27 -1.27)
		(stroke
			(width 0)
			(type default)
		)
	)
	(bus_entry
		(at 163.83 142.24)
		(size -1.27 -1.27)
		(stroke
			(width 0)
			(type default)
		)
	)
	(bus_entry
		(at 163.83 137.16)
		(size -1.27 -1.27)
		(stroke
			(width 0)
			(type default)
		)
	)
	(wire
		(pts
			(xy 194.31 139.7) (xy 200.66 139.7)
		)
		(stroke
			(width 0)
			(type default)
		)
	)
	(wire
		(pts
			(xy 238.76 142.24) (xy 232.41 142.24)
		)
		(stroke
			(width 0)
			(type default)
		)
	)
	(bus
		(pts
			(xy 162.56 138.43) (xy 162.56 140.97)
		)
		(stroke
			(width 0)
			(type default)
		)
	)
	(wire
		(pts
			(xy 238.76 144.78) (xy 232.41 144.78)
		)
		(stroke
			(width 0)
			(type default)
		)
	)
	(wire
		(pts
			(xy 238.76 139.7) (xy 232.41 139.7)
		)
		(stroke
			(width 0)
			(type default)
		)
	)
	(wire
		(pts
			(xy 163.83 142.24) (xy 189.23 142.24)
		)
		(stroke
			(width 0)
			(type default)
		)
	)
	(bus
		(pts
			(xy 162.56 135.89) (xy 162.56 138.43)
		)
		(stroke
			(width 0)
			(type default)
		)
	)
	(wire
		(pts
			(xy 180.34 167.64) (xy 180.34 171.45)
		)
		(stroke
			(width 0)
			(type default)
		)
	)
	(bus
		(pts
			(xy 162.56 134.62) (xy 162.56 135.89)
		)
		(stroke
			(width 0)
			(type default)
		)
	)
	(wire
		(pts
			(xy 194.31 142.24) (xy 200.66 142.24)
		)
		(stroke
			(width 0)
			(type default)
		)
	)
	(wire
		(pts
			(xy 238.76 134.62) (xy 232.41 134.62)
		)
		(stroke
			(width 0)
			(type default)
		)
	)
	(bus
		(pts
			(xy 162.56 134.62) (xy 161.29 133.35)
		)
		(stroke
			(width 0)
			(type default)
		)
	)
	(wire
		(pts
			(xy 238.76 137.16) (xy 232.41 137.16)
		)
		(stroke
			(width 0)
			(type default)
		)
	)
	(wire
		(pts
			(xy 227.33 132.08) (xy 223.52 132.08)
		)
		(stroke
			(width 0)
			(type default)
		)
	)
	(wire
		(pts
			(xy 180.34 121.92) (xy 189.23 121.92)
		)
		(stroke
			(width 0)
			(type default)
		)
	)
	(wire
		(pts
			(xy 162.56 154.94) (xy 189.23 154.94)
		)
		(stroke
			(width 0)
			(type default)
		)
	)
	(wire
		(pts
			(xy 163.83 139.7) (xy 189.23 139.7)
		)
		(stroke
			(width 0)
			(type default)
		)
	)
	(wire
		(pts
			(xy 163.83 137.16) (xy 189.23 137.16)
		)
		(stroke
			(width 0)
			(type default)
		)
	)
	(wire
		(pts
			(xy 189.23 176.53) (xy 189.23 177.8)
		)
		(stroke
			(width 0)
			(type default)
		)
	)
	(wire
		(pts
			(xy 238.76 147.32) (xy 232.41 147.32)
		)
		(stroke
			(width 0)
			(type default)
		)
	)
	(wire
		(pts
			(xy 227.33 149.86) (xy 223.52 149.86)
		)
		(stroke
			(width 0)
			(type default)
		)
	)
	(wire
		(pts
			(xy 180.34 120.65) (xy 180.34 121.92)
		)
		(stroke
			(width 0)
			(type default)
		)
	)
	(wire
		(pts
			(xy 180.34 176.53) (xy 180.34 177.8)
		)
		(stroke
			(width 0)
			(type default)
		)
	)
	(wire
		(pts
			(xy 194.31 154.94) (xy 200.66 154.94)
		)
		(stroke
			(width 0)
			(type default)
		)
	)
	(wire
		(pts
			(xy 180.34 121.92) (xy 180.34 158.75)
		)
		(stroke
			(width 0)
			(type default)
		)
	)
	(wire
		(pts
			(xy 198.12 172.72) (xy 198.12 177.8)
		)
		(stroke
			(width 0)
			(type default)
		)
	)
	(wire
		(pts
			(xy 180.34 163.83) (xy 180.34 167.64)
		)
		(stroke
			(width 0)
			(type default)
		)
	)
	(wire
		(pts
			(xy 227.33 142.24) (xy 223.52 142.24)
		)
		(stroke
			(width 0)
			(type default)
		)
	)
	(wire
		(pts
			(xy 198.12 132.08) (xy 200.66 132.08)
		)
		(stroke
			(width 0)
			(type default)
		)
	)
	(wire
		(pts
			(xy 180.34 167.64) (xy 200.66 167.64)
		)
		(stroke
			(width 0)
			(type default)
		)
	)
	(wire
		(pts
			(xy 238.76 132.08) (xy 232.41 132.08)
		)
		(stroke
			(width 0)
			(type default)
		)
	)
	(bus
		(pts
			(xy 139.7 133.35) (xy 161.29 133.35)
		)
		(stroke
			(width 0)
			(type default)
		)
	)
	(wire
		(pts
			(xy 227.33 147.32) (xy 223.52 147.32)
		)
		(stroke
			(width 0)
			(type default)
		)
	)
	(wire
		(pts
			(xy 227.33 139.7) (xy 223.52 139.7)
		)
		(stroke
			(width 0)
			(type default)
		)
	)
	(wire
		(pts
			(xy 198.12 172.72) (xy 200.66 172.72)
		)
		(stroke
			(width 0)
			(type default)
		)
	)
	(wire
		(pts
			(xy 227.33 137.16) (xy 223.52 137.16)
		)
		(stroke
			(width 0)
			(type default)
		)
	)
	(wire
		(pts
			(xy 189.23 170.18) (xy 200.66 170.18)
		)
		(stroke
			(width 0)
			(type default)
		)
	)
	(wire
		(pts
			(xy 227.33 144.78) (xy 223.52 144.78)
		)
		(stroke
			(width 0)
			(type default)
		)
	)
	(wire
		(pts
			(xy 194.31 137.16) (xy 200.66 137.16)
		)
		(stroke
			(width 0)
			(type default)
		)
	)
	(wire
		(pts
			(xy 227.33 134.62) (xy 223.52 134.62)
		)
		(stroke
			(width 0)
			(type default)
		)
	)
	(wire
		(pts
			(xy 189.23 121.92) (xy 189.23 123.19)
		)
		(stroke
			(width 0)
			(type default)
		)
	)
	(wire
		(pts
			(xy 238.76 149.86) (xy 232.41 149.86)
		)
		(stroke
			(width 0)
			(type default)
		)
	)
	(wire
		(pts
			(xy 189.23 170.18) (xy 189.23 171.45)
		)
		(stroke
			(width 0)
			(type default)
		)
	)
	(wire
		(pts
			(xy 189.23 121.92) (xy 198.12 121.92)
		)
		(stroke
			(width 0)
			(type default)
		)
	)
	(wire
		(pts
			(xy 198.12 121.92) (xy 198.12 132.08)
		)
		(stroke
			(width 0)
			(type default)
		)
	)
	(label "SMBus.~{INT}"
		(at 165.1 142.24 0)
		(effects
			(font
				(size 1.27 1.27)
			)
			(justify left bottom)
		)
	)
	(label "SMBus.SCL"
		(at 165.1 139.7 0)
		(effects
			(font
				(size 1.27 1.27)
			)
			(justify left bottom)
		)
	)
	(label "SMBus.SDA"
		(at 165.1 137.16 0)
		(effects
			(font
				(size 1.27 1.27)
			)
			(justify left bottom)
		)
	)
	(hierarchical_label "GPIOEX2"
		(shape output)
		(at 238.76 137.16 0)
		(effects
			(font
				(size 1.27 1.27)
			)
			(justify left)
		)
	)
	(hierarchical_label "GPIOEX1"
		(shape output)
		(at 238.76 134.62 0)
		(effects
			(font
				(size 1.27 1.27)
			)
			(justify left)
		)
	)
	(hierarchical_label "SMBus{I2C}"
		(shape input)
		(at 139.7 133.35 180)
		(effects
			(font
				(size 1.27 1.27)
			)
			(justify right)
		)
	)
	(hierarchical_label "GPIOEX3"
		(shape output)
		(at 238.76 139.7 0)
		(effects
			(font
				(size 1.27 1.27)
			)
			(justify left)
		)
	)
	(hierarchical_label "GPIOEX7"
		(shape output)
		(at 238.76 149.86 0)
		(effects
			(font
				(size 1.27 1.27)
			)
			(justify left)
		)
	)
	(hierarchical_label "GPIOEX4"
		(shape output)
		(at 238.76 142.24 0)
		(effects
			(font
				(size 1.27 1.27)
			)
			(justify left)
		)
	)
	(hierarchical_label "GPIOEX5"
		(shape output)
		(at 238.76 144.78 0)
		(effects
			(font
				(size 1.27 1.27)
			)
			(justify left)
		)
	)
	(hierarchical_label "GPIOEX0"
		(shape output)
		(at 238.76 132.08 0)
		(effects
			(font
				(size 1.27 1.27)
			)
			(justify left)
		)
	)
	(hierarchical_label "GPIOEX6"
		(shape output)
		(at 238.76 147.32 0)
		(effects
			(font
				(size 1.27 1.27)
			)
			(justify left)
		)
	)
	(hierarchical_label "~{RESET}"
		(shape input)
		(at 162.56 154.94 180)
		(effects
			(font
				(size 1.27 1.27)
			)
			(justify right)
		)
	)
	(symbol
		(lib_id "antmicroResistors0402:R_0R_0402")
		(at 227.33 149.86 0)
		(unit 1)
		(exclude_from_sim no)
		(in_bom yes)
		(on_board yes)
		(dnp no)
		(property "Reference" "R245"
			(at 234.95 148.59 0)
			(effects
				(font
					(size 1.27 1.27)
					(thickness 0.15)
				)
			)
		)
		(property "Value" "R_0R_0402"
			(at 247.65 162.56 0)
			(effects
				(font
					(size 1.27 1.27)
					(thickness 0.15)
				)
				(justify left bottom)
				(hide yes)
			)
		)
		(property "Footprint" "antmicro-footprints:R_0402_1005Metric"
			(at 247.65 165.1 0)
			(effects
				(font
					(size 1.27 1.27)
					(thickness 0.15)
				)
				(justify left bottom)
				(hide yes)
			)
		)
		(property "Datasheet" "https://industrial.panasonic.com/cdbs/www-data/pdf/RDA0000/AOA0000C301.pdf"
			(at 247.65 167.64 0)
			(effects
				(font
					(size 1.27 1.27)
					(thickness 0.15)
				)
				(justify left bottom)
				(hide yes)
			)
		)
		(property "Description" ""
			(at 227.33 149.86 0)
			(effects
				(font
					(size 1.27 1.27)
				)
				(hide yes)
			)
		)
		(property "MPN" "ERJ2GE0R00X"
			(at 247.65 170.18 0)
			(effects
				(font
					(size 1.27 1.27)
					(thickness 0.15)
				)
				(justify left bottom)
				(hide yes)
			)
		)
		(property "Manufacturer" "Panasonic"
			(at 247.65 172.72 0)
			(effects
				(font
					(size 1.27 1.27)
					(thickness 0.15)
				)
				(justify left bottom)
				(hide yes)
			)
		)
		(property "License" "Apache-2.0"
			(at 247.65 175.26 0)
			(effects
				(font
					(size 1.27 1.27)
					(thickness 0.15)
				)
				(justify left bottom)
				(hide yes)
			)
		)
		(property "Author" "Antmicro"
			(at 247.65 177.8 0)
			(effects
				(font
					(size 1.27 1.27)
					(thickness 0.15)
				)
				(justify left bottom)
				(hide yes)
			)
		)
		(property "Val" "0R"
			(at 226.06 148.59 0)
			(effects
				(font
					(size 1.27 1.27)
					(thickness 0.15)
				)
			)
		)
		(property "Tolerance" "~"
			(at 247.65 160.02 0)
			(effects
				(font
					(size 1.27 1.27)
				)
				(justify left bottom)
				(hide yes)
			)
		)
		(property "Current" "1A"
			(at 247.65 180.34 0)
			(effects
				(font
					(size 1.27 1.27)
					(thickness 0.15)
				)
				(justify left bottom)
				(hide yes)
			)
		)
		(property "Public" "False"
			(at 247.65 180.34 0)
			(effects
				(font
					(size 1.27 1.27)
				)
				(justify left bottom)
				(hide yes)
			)
		)
		(pin "1"
		)
		(pin "2"
		)
		(instances
			(project "com-express-7-baseboard"
				(path ""
					(reference "R245")
					(unit 1)
				)
			)
		)
	)
	(symbol
		(lib_id "antmicropower:GND")
		(at 189.23 177.8 0)
		(unit 1)
		(exclude_from_sim no)
		(in_bom yes)
		(on_board yes)
		(dnp no)
		(property "Reference" "#PWR0325"
			(at 198.12 180.34 0)
			(effects
				(font
					(size 1.27 1.27)
					(thickness 0.15)
				)
				(justify left bottom)
				(hide yes)
			)
		)
		(property "Value" "GND"
			(at 189.23 181.61 0)
			(effects
				(font
					(size 1.27 1.27)
					(thickness 0.15)
				)
			)
		)
		(property "Footprint" ""
			(at 198.12 185.42 0)
			(effects
				(font
					(size 1.27 1.27)
					(thickness 0.15)
				)
				(justify left bottom)
				(hide yes)
			)
		)
		(property "Datasheet" ""
			(at 198.12 190.5 0)
			(effects
				(font
					(size 1.27 1.27)
					(thickness 0.15)
				)
				(justify left bottom)
				(hide yes)
			)
		)
		(property "Description" ""
			(at 189.23 177.8 0)
			(effects
				(font
					(size 1.27 1.27)
				)
				(hide yes)
			)
		)
		(property "Author" "Antmicro"
			(at 198.12 185.42 0)
			(effects
				(font
					(size 1.27 1.27)
					(thickness 0.15)
				)
				(justify left bottom)
				(hide yes)
			)
		)
		(property "License" "Apache-2.0"
			(at 198.12 187.96 0)
			(effects
				(font
					(size 1.27 1.27)
					(thickness 0.15)
				)
				(justify left bottom)
				(hide yes)
			)
		)
		(pin "1"
		)
		(instances
			(project "com-express-7-baseboard"
				(path ""
					(reference "#PWR0325")
					(unit 1)
				)
			)
		)
	)
	(symbol
		(lib_id "antmicroResistors0402:R_0R_0402")
		(at 227.33 139.7 0)
		(unit 1)
		(exclude_from_sim no)
		(in_bom yes)
		(on_board yes)
		(dnp no)
		(property "Reference" "R241"
			(at 234.95 138.43 0)
			(effects
				(font
					(size 1.27 1.27)
					(thickness 0.15)
				)
			)
		)
		(property "Value" "R_0R_0402"
			(at 247.65 152.4 0)
			(effects
				(font
					(size 1.27 1.27)
					(thickness 0.15)
				)
				(justify left bottom)
				(hide yes)
			)
		)
		(property "Footprint" "antmicro-footprints:R_0402_1005Metric"
			(at 247.65 154.94 0)
			(effects
				(font
					(size 1.27 1.27)
					(thickness 0.15)
				)
				(justify left bottom)
				(hide yes)
			)
		)
		(property "Datasheet" "https://industrial.panasonic.com/cdbs/www-data/pdf/RDA0000/AOA0000C301.pdf"
			(at 247.65 157.48 0)
			(effects
				(font
					(size 1.27 1.27)
					(thickness 0.15)
				)
				(justify left bottom)
				(hide yes)
			)
		)
		(property "Description" ""
			(at 227.33 139.7 0)
			(effects
				(font
					(size 1.27 1.27)
				)
				(hide yes)
			)
		)
		(property "MPN" "ERJ2GE0R00X"
			(at 247.65 160.02 0)
			(effects
				(font
					(size 1.27 1.27)
					(thickness 0.15)
				)
				(justify left bottom)
				(hide yes)
			)
		)
		(property "Manufacturer" "Panasonic"
			(at 247.65 162.56 0)
			(effects
				(font
					(size 1.27 1.27)
					(thickness 0.15)
				)
				(justify left bottom)
				(hide yes)
			)
		)
		(property "License" "Apache-2.0"
			(at 247.65 165.1 0)
			(effects
				(font
					(size 1.27 1.27)
					(thickness 0.15)
				)
				(justify left bottom)
				(hide yes)
			)
		)
		(property "Author" "Antmicro"
			(at 247.65 167.64 0)
			(effects
				(font
					(size 1.27 1.27)
					(thickness 0.15)
				)
				(justify left bottom)
				(hide yes)
			)
		)
		(property "Val" "0R"
			(at 226.06 138.43 0)
			(effects
				(font
					(size 1.27 1.27)
					(thickness 0.15)
				)
			)
		)
		(property "Tolerance" "~"
			(at 247.65 149.86 0)
			(effects
				(font
					(size 1.27 1.27)
				)
				(justify left bottom)
				(hide yes)
			)
		)
		(property "Current" "1A"
			(at 247.65 170.18 0)
			(effects
				(font
					(size 1.27 1.27)
					(thickness 0.15)
				)
				(justify left bottom)
				(hide yes)
			)
		)
		(property "Public" "False"
			(at 247.65 170.18 0)
			(effects
				(font
					(size 1.27 1.27)
				)
				(justify left bottom)
				(hide yes)
			)
		)
		(pin "1"
		)
		(pin "2"
		)
		(instances
			(project "com-express-7-baseboard"
				(path ""
					(reference "R241")
					(unit 1)
				)
			)
		)
	)
	(symbol
		(lib_id "antmicroResistors0402:R_0R_0402")
		(at 227.33 137.16 0)
		(unit 1)
		(exclude_from_sim no)
		(in_bom yes)
		(on_board yes)
		(dnp no)
		(property "Reference" "R240"
			(at 234.95 135.89 0)
			(effects
				(font
					(size 1.27 1.27)
					(thickness 0.15)
				)
			)
		)
		(property "Value" "R_0R_0402"
			(at 247.65 149.86 0)
			(effects
				(font
					(size 1.27 1.27)
					(thickness 0.15)
				)
				(justify left bottom)
				(hide yes)
			)
		)
		(property "Footprint" "antmicro-footprints:R_0402_1005Metric"
			(at 247.65 152.4 0)
			(effects
				(font
					(size 1.27 1.27)
					(thickness 0.15)
				)
				(justify left bottom)
				(hide yes)
			)
		)
		(property "Datasheet" "https://industrial.panasonic.com/cdbs/www-data/pdf/RDA0000/AOA0000C301.pdf"
			(at 247.65 154.94 0)
			(effects
				(font
					(size 1.27 1.27)
					(thickness 0.15)
				)
				(justify left bottom)
				(hide yes)
			)
		)
		(property "Description" ""
			(at 227.33 137.16 0)
			(effects
				(font
					(size 1.27 1.27)
				)
				(hide yes)
			)
		)
		(property "MPN" "ERJ2GE0R00X"
			(at 247.65 157.48 0)
			(effects
				(font
					(size 1.27 1.27)
					(thickness 0.15)
				)
				(justify left bottom)
				(hide yes)
			)
		)
		(property "Manufacturer" "Panasonic"
			(at 247.65 160.02 0)
			(effects
				(font
					(size 1.27 1.27)
					(thickness 0.15)
				)
				(justify left bottom)
				(hide yes)
			)
		)
		(property "License" "Apache-2.0"
			(at 247.65 162.56 0)
			(effects
				(font
					(size 1.27 1.27)
					(thickness 0.15)
				)
				(justify left bottom)
				(hide yes)
			)
		)
		(property "Author" "Antmicro"
			(at 247.65 165.1 0)
			(effects
				(font
					(size 1.27 1.27)
					(thickness 0.15)
				)
				(justify left bottom)
				(hide yes)
			)
		)
		(property "Val" "0R"
			(at 226.06 135.89 0)
			(effects
				(font
					(size 1.27 1.27)
					(thickness 0.15)
				)
			)
		)
		(property "Tolerance" "~"
			(at 247.65 147.32 0)
			(effects
				(font
					(size 1.27 1.27)
				)
				(justify left bottom)
				(hide yes)
			)
		)
		(property "Current" "1A"
			(at 247.65 167.64 0)
			(effects
				(font
					(size 1.27 1.27)
					(thickness 0.15)
				)
				(justify left bottom)
				(hide yes)
			)
		)
		(property "Public" "False"
			(at 247.65 167.64 0)
			(effects
				(font
					(size 1.27 1.27)
				)
				(justify left bottom)
				(hide yes)
			)
		)
		(pin "1"
		)
		(pin "2"
		)
		(instances
			(project "com-express-7-baseboard"
				(path ""
					(reference "R240")
					(unit 1)
				)
			)
		)
	)
	(symbol
		(lib_id "antmicropower:GND")
		(at 189.23 128.27 0)
		(unit 1)
		(exclude_from_sim no)
		(in_bom yes)
		(on_board yes)
		(dnp no)
		(property "Reference" "#PWR0324"
			(at 198.12 130.81 0)
			(effects
				(font
					(size 1.27 1.27)
					(thickness 0.15)
				)
				(justify left bottom)
				(hide yes)
			)
		)
		(property "Value" "GND"
			(at 189.23 132.08 0)
			(effects
				(font
					(size 1.27 1.27)
					(thickness 0.15)
				)
			)
		)
		(property "Footprint" ""
			(at 198.12 135.89 0)
			(effects
				(font
					(size 1.27 1.27)
					(thickness 0.15)
				)
				(justify left bottom)
				(hide yes)
			)
		)
		(property "Datasheet" ""
			(at 198.12 140.97 0)
			(effects
				(font
					(size 1.27 1.27)
					(thickness 0.15)
				)
				(justify left bottom)
				(hide yes)
			)
		)
		(property "Description" ""
			(at 189.23 128.27 0)
			(effects
				(font
					(size 1.27 1.27)
				)
				(hide yes)
			)
		)
		(property "Author" "Antmicro"
			(at 198.12 135.89 0)
			(effects
				(font
					(size 1.27 1.27)
					(thickness 0.15)
				)
				(justify left bottom)
				(hide yes)
			)
		)
		(property "License" "Apache-2.0"
			(at 198.12 138.43 0)
			(effects
				(font
					(size 1.27 1.27)
					(thickness 0.15)
				)
				(justify left bottom)
				(hide yes)
			)
		)
		(pin "1"
		)
		(instances
			(project "com-express-7-baseboard"
				(path ""
					(reference "#PWR0324")
					(unit 1)
				)
			)
		)
	)
	(symbol
		(lib_id "antmicroResistors0402:R_0R_0402")
		(at 227.33 147.32 0)
		(unit 1)
		(exclude_from_sim no)
		(in_bom yes)
		(on_board yes)
		(dnp no)
		(property "Reference" "R244"
			(at 234.95 146.05 0)
			(effects
				(font
					(size 1.27 1.27)
					(thickness 0.15)
				)
			)
		)
		(property "Value" "R_0R_0402"
			(at 247.65 160.02 0)
			(effects
				(font
					(size 1.27 1.27)
					(thickness 0.15)
				)
				(justify left bottom)
				(hide yes)
			)
		)
		(property "Footprint" "antmicro-footprints:R_0402_1005Metric"
			(at 247.65 162.56 0)
			(effects
				(font
					(size 1.27 1.27)
					(thickness 0.15)
				)
				(justify left bottom)
				(hide yes)
			)
		)
		(property "Datasheet" "https://industrial.panasonic.com/cdbs/www-data/pdf/RDA0000/AOA0000C301.pdf"
			(at 247.65 165.1 0)
			(effects
				(font
					(size 1.27 1.27)
					(thickness 0.15)
				)
				(justify left bottom)
				(hide yes)
			)
		)
		(property "Description" ""
			(at 227.33 147.32 0)
			(effects
				(font
					(size 1.27 1.27)
				)
				(hide yes)
			)
		)
		(property "MPN" "ERJ2GE0R00X"
			(at 247.65 167.64 0)
			(effects
				(font
					(size 1.27 1.27)
					(thickness 0.15)
				)
				(justify left bottom)
				(hide yes)
			)
		)
		(property "Manufacturer" "Panasonic"
			(at 247.65 170.18 0)
			(effects
				(font
					(size 1.27 1.27)
					(thickness 0.15)
				)
				(justify left bottom)
				(hide yes)
			)
		)
		(property "License" "Apache-2.0"
			(at 247.65 172.72 0)
			(effects
				(font
					(size 1.27 1.27)
					(thickness 0.15)
				)
				(justify left bottom)
				(hide yes)
			)
		)
		(property "Author" "Antmicro"
			(at 247.65 175.26 0)
			(effects
				(font
					(size 1.27 1.27)
					(thickness 0.15)
				)
				(justify left bottom)
				(hide yes)
			)
		)
		(property "Val" "0R"
			(at 226.06 146.05 0)
			(effects
				(font
					(size 1.27 1.27)
					(thickness 0.15)
				)
			)
		)
		(property "Tolerance" "~"
			(at 247.65 157.48 0)
			(effects
				(font
					(size 1.27 1.27)
				)
				(justify left bottom)
				(hide yes)
			)
		)
		(property "Current" "1A"
			(at 247.65 177.8 0)
			(effects
				(font
					(size 1.27 1.27)
					(thickness 0.15)
				)
				(justify left bottom)
				(hide yes)
			)
		)
		(property "Public" "False"
			(at 247.65 177.8 0)
			(effects
				(font
					(size 1.27 1.27)
				)
				(justify left bottom)
				(hide yes)
			)
		)
		(pin "1"
		)
		(pin "2"
		)
		(instances
			(project "com-express-7-baseboard"
				(path ""
					(reference "R244")
					(unit 1)
				)
			)
		)
	)
	(symbol
		(lib_id "antmicroResistors0402:R_0R_0402")
		(at 189.23 154.94 0)
		(unit 1)
		(exclude_from_sim no)
		(in_bom yes)
		(on_board yes)
		(dnp no)
		(property "Reference" "R236"
			(at 186.69 153.67 0)
			(effects
				(font
					(size 1.27 1.27)
					(thickness 0.15)
				)
			)
		)
		(property "Value" "R_0R_0402"
			(at 209.55 167.64 0)
			(effects
				(font
					(size 1.27 1.27)
					(thickness 0.15)
				)
				(justify left bottom)
				(hide yes)
			)
		)
		(property "Footprint" "antmicro-footprints:R_0402_1005Metric"
			(at 209.55 170.18 0)
			(effects
				(font
					(size 1.27 1.27)
					(thickness 0.15)
				)
				(justify left bottom)
				(hide yes)
			)
		)
		(property "Datasheet" "https://industrial.panasonic.com/cdbs/www-data/pdf/RDA0000/AOA0000C301.pdf"
			(at 209.55 172.72 0)
			(effects
				(font
					(size 1.27 1.27)
					(thickness 0.15)
				)
				(justify left bottom)
				(hide yes)
			)
		)
		(property "Description" ""
			(at 189.23 154.94 0)
			(effects
				(font
					(size 1.27 1.27)
				)
				(hide yes)
			)
		)
		(property "MPN" "ERJ2GE0R00X"
			(at 209.55 175.26 0)
			(effects
				(font
					(size 1.27 1.27)
					(thickness 0.15)
				)
				(justify left bottom)
				(hide yes)
			)
		)
		(property "Manufacturer" "Panasonic"
			(at 209.55 177.8 0)
			(effects
				(font
					(size 1.27 1.27)
					(thickness 0.15)
				)
				(justify left bottom)
				(hide yes)
			)
		)
		(property "License" "Apache-2.0"
			(at 209.55 180.34 0)
			(effects
				(font
					(size 1.27 1.27)
					(thickness 0.15)
				)
				(justify left bottom)
				(hide yes)
			)
		)
		(property "Author" "Antmicro"
			(at 209.55 182.88 0)
			(effects
				(font
					(size 1.27 1.27)
					(thickness 0.15)
				)
				(justify left bottom)
				(hide yes)
			)
		)
		(property "Val" "0R"
			(at 195.58 153.67 0)
			(effects
				(font
					(size 1.27 1.27)
					(thickness 0.15)
				)
			)
		)
		(property "Tolerance" "~"
			(at 209.55 165.1 0)
			(effects
				(font
					(size 1.27 1.27)
				)
				(justify left bottom)
				(hide yes)
			)
		)
		(property "Current" "1A"
			(at 209.55 185.42 0)
			(effects
				(font
					(size 1.27 1.27)
					(thickness 0.15)
				)
				(justify left bottom)
				(hide yes)
			)
		)
		(property "Public" "False"
			(at 209.55 185.42 0)
			(effects
				(font
					(size 1.27 1.27)
				)
				(justify left bottom)
				(hide yes)
			)
		)
		(pin "1"
		)
		(pin "2"
		)
		(instances
			(project "com-express-7-baseboard"
				(path ""
					(reference "R236")
					(unit 1)
				)
			)
		)
	)
	(symbol
		(lib_id "antmicroResistors0402:R_0R_0402")
		(at 189.23 139.7 0)
		(unit 1)
		(exclude_from_sim no)
		(in_bom yes)
		(on_board yes)
		(dnp no)
		(property "Reference" "R234"
			(at 186.69 138.43 0)
			(effects
				(font
					(size 1.27 1.27)
					(thickness 0.15)
				)
			)
		)
		(property "Value" "R_0R_0402"
			(at 209.55 152.4 0)
			(effects
				(font
					(size 1.27 1.27)
					(thickness 0.15)
				)
				(justify left bottom)
				(hide yes)
			)
		)
		(property "Footprint" "antmicro-footprints:R_0402_1005Metric"
			(at 209.55 154.94 0)
			(effects
				(font
					(size 1.27 1.27)
					(thickness 0.15)
				)
				(justify left bottom)
				(hide yes)
			)
		)
		(property "Datasheet" "https://industrial.panasonic.com/cdbs/www-data/pdf/RDA0000/AOA0000C301.pdf"
			(at 209.55 157.48 0)
			(effects
				(font
					(size 1.27 1.27)
					(thickness 0.15)
				)
				(justify left bottom)
				(hide yes)
			)
		)
		(property "Description" ""
			(at 189.23 139.7 0)
			(effects
				(font
					(size 1.27 1.27)
				)
				(hide yes)
			)
		)
		(property "MPN" "ERJ2GE0R00X"
			(at 209.55 160.02 0)
			(effects
				(font
					(size 1.27 1.27)
					(thickness 0.15)
				)
				(justify left bottom)
				(hide yes)
			)
		)
		(property "Manufacturer" "Panasonic"
			(at 209.55 162.56 0)
			(effects
				(font
					(size 1.27 1.27)
					(thickness 0.15)
				)
				(justify left bottom)
				(hide yes)
			)
		)
		(property "License" "Apache-2.0"
			(at 209.55 165.1 0)
			(effects
				(font
					(size 1.27 1.27)
					(thickness 0.15)
				)
				(justify left bottom)
				(hide yes)
			)
		)
		(property "Author" "Antmicro"
			(at 209.55 167.64 0)
			(effects
				(font
					(size 1.27 1.27)
					(thickness 0.15)
				)
				(justify left bottom)
				(hide yes)
			)
		)
		(property "Val" "0R"
			(at 195.58 138.43 0)
			(effects
				(font
					(size 1.27 1.27)
					(thickness 0.15)
				)
			)
		)
		(property "Tolerance" "~"
			(at 209.55 149.86 0)
			(effects
				(font
					(size 1.27 1.27)
				)
				(justify left bottom)
				(hide yes)
			)
		)
		(property "Current" "1A"
			(at 209.55 170.18 0)
			(effects
				(font
					(size 1.27 1.27)
					(thickness 0.15)
				)
				(justify left bottom)
				(hide yes)
			)
		)
		(property "Public" "False"
			(at 209.55 170.18 0)
			(effects
				(font
					(size 1.27 1.27)
				)
				(justify left bottom)
				(hide yes)
			)
		)
		(pin "2"
		)
		(pin "1"
		)
		(instances
			(project "com-express-7-baseboard"
				(path ""
					(reference "R234")
					(unit 1)
				)
			)
		)
	)
	(symbol
		(lib_id "antmicroResistors0402:R_0R_0402")
		(at 227.33 142.24 0)
		(unit 1)
		(exclude_from_sim no)
		(in_bom yes)
		(on_board yes)
		(dnp no)
		(property "Reference" "R242"
			(at 234.95 140.97 0)
			(effects
				(font
					(size 1.27 1.27)
					(thickness 0.15)
				)
			)
		)
		(property "Value" "R_0R_0402"
			(at 247.65 154.94 0)
			(effects
				(font
					(size 1.27 1.27)
					(thickness 0.15)
				)
				(justify left bottom)
				(hide yes)
			)
		)
		(property "Footprint" "antmicro-footprints:R_0402_1005Metric"
			(at 247.65 157.48 0)
			(effects
				(font
					(size 1.27 1.27)
					(thickness 0.15)
				)
				(justify left bottom)
				(hide yes)
			)
		)
		(property "Datasheet" "https://industrial.panasonic.com/cdbs/www-data/pdf/RDA0000/AOA0000C301.pdf"
			(at 247.65 160.02 0)
			(effects
				(font
					(size 1.27 1.27)
					(thickness 0.15)
				)
				(justify left bottom)
				(hide yes)
			)
		)
		(property "Description" ""
			(at 227.33 142.24 0)
			(effects
				(font
					(size 1.27 1.27)
				)
				(hide yes)
			)
		)
		(property "MPN" "ERJ2GE0R00X"
			(at 247.65 162.56 0)
			(effects
				(font
					(size 1.27 1.27)
					(thickness 0.15)
				)
				(justify left bottom)
				(hide yes)
			)
		)
		(property "Manufacturer" "Panasonic"
			(at 247.65 165.1 0)
			(effects
				(font
					(size 1.27 1.27)
					(thickness 0.15)
				)
				(justify left bottom)
				(hide yes)
			)
		)
		(property "License" "Apache-2.0"
			(at 247.65 167.64 0)
			(effects
				(font
					(size 1.27 1.27)
					(thickness 0.15)
				)
				(justify left bottom)
				(hide yes)
			)
		)
		(property "Author" "Antmicro"
			(at 247.65 170.18 0)
			(effects
				(font
					(size 1.27 1.27)
					(thickness 0.15)
				)
				(justify left bottom)
				(hide yes)
			)
		)
		(property "Val" "0R"
			(at 226.06 140.97 0)
			(effects
				(font
					(size 1.27 1.27)
					(thickness 0.15)
				)
			)
		)
		(property "Tolerance" "~"
			(at 247.65 152.4 0)
			(effects
				(font
					(size 1.27 1.27)
				)
				(justify left bottom)
				(hide yes)
			)
		)
		(property "Current" "1A"
			(at 247.65 172.72 0)
			(effects
				(font
					(size 1.27 1.27)
					(thickness 0.15)
				)
				(justify left bottom)
				(hide yes)
			)
		)
		(property "Public" "False"
			(at 247.65 172.72 0)
			(effects
				(font
					(size 1.27 1.27)
				)
				(justify left bottom)
				(hide yes)
			)
		)
		(pin "1"
		)
		(pin "2"
		)
		(instances
			(project "com-express-7-baseboard"
				(path ""
					(reference "R242")
					(unit 1)
				)
			)
		)
	)
	(symbol
		(lib_id "antmicroResistors0402:R_0R_0402")
		(at 189.23 176.53 90)
		(unit 1)
		(exclude_from_sim no)
		(in_bom yes)
		(on_board yes)
		(dnp no)
		(property "Reference" "R237"
			(at 190.5 172.72 90)
			(effects
				(font
					(size 1.27 1.27)
					(thickness 0.15)
				)
				(justify right)
			)
		)
		(property "Value" "R_0R_0402"
			(at 201.93 156.21 0)
			(effects
				(font
					(size 1.27 1.27)
					(thickness 0.15)
				)
				(justify left bottom)
				(hide yes)
			)
		)
		(property "Footprint" "antmicro-footprints:R_0402_1005Metric"
			(at 204.47 156.21 0)
			(effects
				(font
					(size 1.27 1.27)
					(thickness 0.15)
				)
				(justify left bottom)
				(hide yes)
			)
		)
		(property "Datasheet" "https://industrial.panasonic.com/cdbs/www-data/pdf/RDA0000/AOA0000C301.pdf"
			(at 207.01 156.21 0)
			(effects
				(font
					(size 1.27 1.27)
					(thickness 0.15)
				)
				(justify left bottom)
				(hide yes)
			)
		)
		(property "Description" ""
			(at 189.23 176.53 0)
			(effects
				(font
					(size 1.27 1.27)
				)
				(hide yes)
			)
		)
		(property "MPN" "ERJ2GE0R00X"
			(at 209.55 156.21 0)
			(effects
				(font
					(size 1.27 1.27)
					(thickness 0.15)
				)
				(justify left bottom)
				(hide yes)
			)
		)
		(property "Manufacturer" "Panasonic"
			(at 212.09 156.21 0)
			(effects
				(font
					(size 1.27 1.27)
					(thickness 0.15)
				)
				(justify left bottom)
				(hide yes)
			)
		)
		(property "License" "Apache-2.0"
			(at 214.63 156.21 0)
			(effects
				(font
					(size 1.27 1.27)
					(thickness 0.15)
				)
				(justify left bottom)
				(hide yes)
			)
		)
		(property "Author" "Antmicro"
			(at 217.17 156.21 0)
			(effects
				(font
					(size 1.27 1.27)
					(thickness 0.15)
				)
				(justify left bottom)
				(hide yes)
			)
		)
		(property "Val" "0R"
			(at 190.5 175.26 90)
			(effects
				(font
					(size 1.27 1.27)
					(thickness 0.15)
				)
				(justify right)
			)
		)
		(property "Tolerance" "~"
			(at 199.39 156.21 0)
			(effects
				(font
					(size 1.27 1.27)
				)
				(justify left bottom)
				(hide yes)
			)
		)
		(property "Current" "1A"
			(at 219.71 156.21 0)
			(effects
				(font
					(size 1.27 1.27)
					(thickness 0.15)
				)
				(justify left bottom)
				(hide yes)
			)
		)
		(property "Public" "False"
			(at 219.71 156.21 0)
			(effects
				(font
					(size 1.27 1.27)
				)
				(justify left bottom)
				(hide yes)
			)
		)
		(pin "2"
		)
		(pin "1"
		)
		(instances
			(project "com-express-7-baseboard"
				(path ""
					(reference "R237")
					(unit 1)
				)
			)
		)
	)
	(symbol
		(lib_id "antmicroResistors0402:R_0R_0402")
		(at 189.23 142.24 0)
		(unit 1)
		(exclude_from_sim no)
		(in_bom yes)
		(on_board yes)
		(dnp no)
		(property "Reference" "R235"
			(at 186.69 140.97 0)
			(effects
				(font
					(size 1.27 1.27)
					(thickness 0.15)
				)
			)
		)
		(property "Value" "R_0R_0402"
			(at 209.55 154.94 0)
			(effects
				(font
					(size 1.27 1.27)
					(thickness 0.15)
				)
				(justify left bottom)
				(hide yes)
			)
		)
		(property "Footprint" "antmicro-footprints:R_0402_1005Metric"
			(at 209.55 157.48 0)
			(effects
				(font
					(size 1.27 1.27)
					(thickness 0.15)
				)
				(justify left bottom)
				(hide yes)
			)
		)
		(property "Datasheet" "https://industrial.panasonic.com/cdbs/www-data/pdf/RDA0000/AOA0000C301.pdf"
			(at 209.55 160.02 0)
			(effects
				(font
					(size 1.27 1.27)
					(thickness 0.15)
				)
				(justify left bottom)
				(hide yes)
			)
		)
		(property "Description" ""
			(at 189.23 142.24 0)
			(effects
				(font
					(size 1.27 1.27)
				)
				(hide yes)
			)
		)
		(property "MPN" "ERJ2GE0R00X"
			(at 209.55 162.56 0)
			(effects
				(font
					(size 1.27 1.27)
					(thickness 0.15)
				)
				(justify left bottom)
				(hide yes)
			)
		)
		(property "Manufacturer" "Panasonic"
			(at 209.55 165.1 0)
			(effects
				(font
					(size 1.27 1.27)
					(thickness 0.15)
				)
				(justify left bottom)
				(hide yes)
			)
		)
		(property "License" "Apache-2.0"
			(at 209.55 167.64 0)
			(effects
				(font
					(size 1.27 1.27)
					(thickness 0.15)
				)
				(justify left bottom)
				(hide yes)
			)
		)
		(property "Author" "Antmicro"
			(at 209.55 170.18 0)
			(effects
				(font
					(size 1.27 1.27)
					(thickness 0.15)
				)
				(justify left bottom)
				(hide yes)
			)
		)
		(property "Val" "0R"
			(at 195.58 140.97 0)
			(effects
				(font
					(size 1.27 1.27)
					(thickness 0.15)
				)
			)
		)
		(property "Tolerance" "~"
			(at 209.55 152.4 0)
			(effects
				(font
					(size 1.27 1.27)
				)
				(justify left bottom)
				(hide yes)
			)
		)
		(property "Current" "1A"
			(at 209.55 172.72 0)
			(effects
				(font
					(size 1.27 1.27)
					(thickness 0.15)
				)
				(justify left bottom)
				(hide yes)
			)
		)
		(property "Public" "False"
			(at 209.55 172.72 0)
			(effects
				(font
					(size 1.27 1.27)
				)
				(justify left bottom)
				(hide yes)
			)
		)
		(pin "2"
		)
		(pin "1"
		)
		(instances
			(project "com-express-7-baseboard"
				(path ""
					(reference "R235")
					(unit 1)
				)
			)
		)
	)
	(symbol
		(lib_id "antmicroResistors0402:R_0R_0402")
		(at 227.33 134.62 0)
		(unit 1)
		(exclude_from_sim no)
		(in_bom yes)
		(on_board yes)
		(dnp no)
		(property "Reference" "R239"
			(at 234.95 133.35 0)
			(effects
				(font
					(size 1.27 1.27)
					(thickness 0.15)
				)
			)
		)
		(property "Value" "R_0R_0402"
			(at 247.65 147.32 0)
			(effects
				(font
					(size 1.27 1.27)
					(thickness 0.15)
				)
				(justify left bottom)
				(hide yes)
			)
		)
		(property "Footprint" "antmicro-footprints:R_0402_1005Metric"
			(at 247.65 149.86 0)
			(effects
				(font
					(size 1.27 1.27)
					(thickness 0.15)
				)
				(justify left bottom)
				(hide yes)
			)
		)
		(property "Datasheet" "https://industrial.panasonic.com/cdbs/www-data/pdf/RDA0000/AOA0000C301.pdf"
			(at 247.65 152.4 0)
			(effects
				(font
					(size 1.27 1.27)
					(thickness 0.15)
				)
				(justify left bottom)
				(hide yes)
			)
		)
		(property "Description" ""
			(at 227.33 134.62 0)
			(effects
				(font
					(size 1.27 1.27)
				)
				(hide yes)
			)
		)
		(property "MPN" "ERJ2GE0R00X"
			(at 247.65 154.94 0)
			(effects
				(font
					(size 1.27 1.27)
					(thickness 0.15)
				)
				(justify left bottom)
				(hide yes)
			)
		)
		(property "Manufacturer" "Panasonic"
			(at 247.65 157.48 0)
			(effects
				(font
					(size 1.27 1.27)
					(thickness 0.15)
				)
				(justify left bottom)
				(hide yes)
			)
		)
		(property "License" "Apache-2.0"
			(at 247.65 160.02 0)
			(effects
				(font
					(size 1.27 1.27)
					(thickness 0.15)
				)
				(justify left bottom)
				(hide yes)
			)
		)
		(property "Author" "Antmicro"
			(at 247.65 162.56 0)
			(effects
				(font
					(size 1.27 1.27)
					(thickness 0.15)
				)
				(justify left bottom)
				(hide yes)
			)
		)
		(property "Val" "0R"
			(at 226.06 133.35 0)
			(effects
				(font
					(size 1.27 1.27)
					(thickness 0.15)
				)
			)
		)
		(property "Tolerance" "~"
			(at 247.65 144.78 0)
			(effects
				(font
					(size 1.27 1.27)
				)
				(justify left bottom)
				(hide yes)
			)
		)
		(property "Current" "1A"
			(at 247.65 165.1 0)
			(effects
				(font
					(size 1.27 1.27)
					(thickness 0.15)
				)
				(justify left bottom)
				(hide yes)
			)
		)
		(property "Public" "False"
			(at 247.65 165.1 0)
			(effects
				(font
					(size 1.27 1.27)
				)
				(justify left bottom)
				(hide yes)
			)
		)
		(pin "1"
		)
		(pin "2"
		)
		(instances
			(project "com-express-7-baseboard"
				(path ""
					(reference "R239")
					(unit 1)
				)
			)
		)
	)
	(symbol
		(lib_id "antmicroInterfaceIOExpanders:PCA9539AHF")
		(at 200.66 132.08 0)
		(unit 1)
		(exclude_from_sim no)
		(in_bom yes)
		(on_board yes)
		(dnp no)
		(fields_autoplaced yes)
		(property "Reference" "U41"
			(at 212.09 124.46 0)
			(effects
				(font
					(size 1.27 1.27)
					(thickness 0.15)
				)
			)
		)
		(property "Value" "PCA9539AHF"
			(at 233.68 142.24 0)
			(effects
				(font
					(size 1.27 1.27)
					(thickness 0.15)
				)
				(justify left bottom)
				(hide yes)
			)
		)
		(property "Footprint" "antmicro-footprints:QFN-24-1EP_4x4mm_P0.5_EP2.1x2.1mm"
			(at 233.68 144.78 0)
			(effects
				(font
					(size 1.27 1.27)
					(thickness 0.15)
				)
				(justify left bottom)
				(hide yes)
			)
		)
		(property "Datasheet" "https://www.nxp.com/docs/en/data-sheet/PCA9539A.pdf"
			(at 233.68 147.32 0)
			(effects
				(font
					(size 1.27 1.27)
					(thickness 0.15)
				)
				(justify left bottom)
				(hide yes)
			)
		)
		(property "Description" ""
			(at 200.66 132.08 0)
			(effects
				(font
					(size 1.27 1.27)
				)
				(hide yes)
			)
		)
		(property "MPN" "PCA9539AHF,128"
			(at 212.09 127 0)
			(effects
				(font
					(size 1.27 1.27)
					(thickness 0.15)
				)
			)
		)
		(property "Manufacturer" "NXP"
			(at 233.68 149.86 0)
			(effects
				(font
					(size 1.27 1.27)
					(thickness 0.15)
				)
				(justify left bottom)
				(hide yes)
			)
		)
		(property "Author" "Antmicro"
			(at 233.68 152.4 0)
			(effects
				(font
					(size 1.27 1.27)
					(thickness 0.15)
				)
				(justify left bottom)
				(hide yes)
			)
		)
		(property "License" "Apache-2.0"
			(at 233.68 154.94 0)
			(effects
				(font
					(size 1.27 1.27)
					(thickness 0.15)
				)
				(justify left bottom)
				(hide yes)
			)
		)
		(pin "17"
		)
		(pin "18"
		)
		(pin "4"
		)
		(pin "3"
		)
		(pin "9"
		)
		(pin "5"
		)
		(pin "6"
		)
		(pin "15"
		)
		(pin "20"
		)
		(pin "2"
		)
		(pin "13"
		)
		(pin "12"
		)
		(pin "24"
		)
		(pin "8"
		)
		(pin "25"
		)
		(pin "22"
		)
		(pin "23"
		)
		(pin "11"
		)
		(pin "10"
		)
		(pin "14"
		)
		(pin "1"
		)
		(pin "7"
		)
		(pin "21"
		)
		(pin "16"
		)
		(pin "19"
		)
		(instances
			(project "com-express-7-baseboard"
				(path ""
					(reference "U41")
					(unit 1)
				)
			)
		)
	)
	(symbol
		(lib_id "antmicroResistors0402:R_0R_0402")
		(at 227.33 132.08 0)
		(unit 1)
		(exclude_from_sim no)
		(in_bom yes)
		(on_board yes)
		(dnp no)
		(property "Reference" "R238"
			(at 234.95 130.81 0)
			(effects
				(font
					(size 1.27 1.27)
					(thickness 0.15)
				)
			)
		)
		(property "Value" "R_0R_0402"
			(at 247.65 144.78 0)
			(effects
				(font
					(size 1.27 1.27)
					(thickness 0.15)
				)
				(justify left bottom)
				(hide yes)
			)
		)
		(property "Footprint" "antmicro-footprints:R_0402_1005Metric"
			(at 247.65 147.32 0)
			(effects
				(font
					(size 1.27 1.27)
					(thickness 0.15)
				)
				(justify left bottom)
				(hide yes)
			)
		)
		(property "Datasheet" "https://industrial.panasonic.com/cdbs/www-data/pdf/RDA0000/AOA0000C301.pdf"
			(at 247.65 149.86 0)
			(effects
				(font
					(size 1.27 1.27)
					(thickness 0.15)
				)
				(justify left bottom)
				(hide yes)
			)
		)
		(property "Description" ""
			(at 227.33 132.08 0)
			(effects
				(font
					(size 1.27 1.27)
				)
				(hide yes)
			)
		)
		(property "MPN" "ERJ2GE0R00X"
			(at 247.65 152.4 0)
			(effects
				(font
					(size 1.27 1.27)
					(thickness 0.15)
				)
				(justify left bottom)
				(hide yes)
			)
		)
		(property "Manufacturer" "Panasonic"
			(at 247.65 154.94 0)
			(effects
				(font
					(size 1.27 1.27)
					(thickness 0.15)
				)
				(justify left bottom)
				(hide yes)
			)
		)
		(property "License" "Apache-2.0"
			(at 247.65 157.48 0)
			(effects
				(font
					(size 1.27 1.27)
					(thickness 0.15)
				)
				(justify left bottom)
				(hide yes)
			)
		)
		(property "Author" "Antmicro"
			(at 247.65 160.02 0)
			(effects
				(font
					(size 1.27 1.27)
					(thickness 0.15)
				)
				(justify left bottom)
				(hide yes)
			)
		)
		(property "Val" "0R"
			(at 226.06 130.81 0)
			(effects
				(font
					(size 1.27 1.27)
					(thickness 0.15)
				)
			)
		)
		(property "Tolerance" "~"
			(at 247.65 142.24 0)
			(effects
				(font
					(size 1.27 1.27)
				)
				(justify left bottom)
				(hide yes)
			)
		)
		(property "Current" "1A"
			(at 247.65 162.56 0)
			(effects
				(font
					(size 1.27 1.27)
					(thickness 0.15)
				)
				(justify left bottom)
				(hide yes)
			)
		)
		(property "Public" "False"
			(at 247.65 162.56 0)
			(effects
				(font
					(size 1.27 1.27)
				)
				(justify left bottom)
				(hide yes)
			)
		)
		(pin "1"
		)
		(pin "2"
		)
		(instances
			(project "com-express-7-baseboard"
				(path ""
					(reference "R238")
					(unit 1)
				)
			)
		)
	)
	(symbol
		(lib_id "antmicroResistors0402:R_0R_0402")
		(at 180.34 163.83 90)
		(unit 1)
		(exclude_from_sim no)
		(in_bom yes)
		(on_board yes)
		(dnp yes)
		(property "Reference" "R231"
			(at 179.07 158.75 90)
			(effects
				(font
					(size 1.27 1.27)
					(thickness 0.15)
				)
				(justify left)
			)
		)
		(property "Value" "R_0R_0402"
			(at 193.04 143.51 0)
			(effects
				(font
					(size 1.27 1.27)
					(thickness 0.15)
				)
				(justify left bottom)
				(hide yes)
			)
		)
		(property "Footprint" "antmicro-footprints:R_0402_1005Metric"
			(at 195.58 143.51 0)
			(effects
				(font
					(size 1.27 1.27)
					(thickness 0.15)
				)
				(justify left bottom)
				(hide yes)
			)
		)
		(property "Datasheet" "https://industrial.panasonic.com/cdbs/www-data/pdf/RDA0000/AOA0000C301.pdf"
			(at 198.12 143.51 0)
			(effects
				(font
					(size 1.27 1.27)
					(thickness 0.15)
				)
				(justify left bottom)
				(hide yes)
			)
		)
		(property "Description" ""
			(at 180.34 163.83 0)
			(effects
				(font
					(size 1.27 1.27)
				)
				(hide yes)
			)
		)
		(property "MPN" "ERJ2GE0R00X"
			(at 200.66 143.51 0)
			(effects
				(font
					(size 1.27 1.27)
					(thickness 0.15)
				)
				(justify left bottom)
				(hide yes)
			)
		)
		(property "Manufacturer" "Panasonic"
			(at 203.2 143.51 0)
			(effects
				(font
					(size 1.27 1.27)
					(thickness 0.15)
				)
				(justify left bottom)
				(hide yes)
			)
		)
		(property "License" "Apache-2.0"
			(at 205.74 143.51 0)
			(effects
				(font
					(size 1.27 1.27)
					(thickness 0.15)
				)
				(justify left bottom)
				(hide yes)
			)
		)
		(property "Author" "Antmicro"
			(at 208.28 143.51 0)
			(effects
				(font
					(size 1.27 1.27)
					(thickness 0.15)
				)
				(justify left bottom)
				(hide yes)
			)
		)
		(property "Val" "0R"
			(at 179.07 161.29 90)
			(effects
				(font
					(size 1.27 1.27)
					(thickness 0.15)
				)
				(justify left)
			)
		)
		(property "Tolerance" "~"
			(at 190.5 143.51 0)
			(effects
				(font
					(size 1.27 1.27)
				)
				(justify left bottom)
				(hide yes)
			)
		)
		(property "Current" "1A"
			(at 210.82 143.51 0)
			(effects
				(font
					(size 1.27 1.27)
					(thickness 0.15)
				)
				(justify left bottom)
				(hide yes)
			)
		)
		(property "Public" "False"
			(at 210.82 143.51 0)
			(effects
				(font
					(size 1.27 1.27)
				)
				(justify left bottom)
				(hide yes)
			)
		)
		(pin "2"
		)
		(pin "1"
		)
		(instances
			(project "com-express-7-baseboard"
				(path ""
					(reference "R231")
					(unit 1)
				)
			)
		)
	)
	(symbol
		(lib_id "antmicroResistors0402:R_0R_0402")
		(at 227.33 144.78 0)
		(unit 1)
		(exclude_from_sim no)
		(in_bom yes)
		(on_board yes)
		(dnp no)
		(property "Reference" "R243"
			(at 234.95 143.51 0)
			(effects
				(font
					(size 1.27 1.27)
					(thickness 0.15)
				)
			)
		)
		(property "Value" "R_0R_0402"
			(at 247.65 157.48 0)
			(effects
				(font
					(size 1.27 1.27)
					(thickness 0.15)
				)
				(justify left bottom)
				(hide yes)
			)
		)
		(property "Footprint" "antmicro-footprints:R_0402_1005Metric"
			(at 247.65 160.02 0)
			(effects
				(font
					(size 1.27 1.27)
					(thickness 0.15)
				)
				(justify left bottom)
				(hide yes)
			)
		)
		(property "Datasheet" "https://industrial.panasonic.com/cdbs/www-data/pdf/RDA0000/AOA0000C301.pdf"
			(at 247.65 162.56 0)
			(effects
				(font
					(size 1.27 1.27)
					(thickness 0.15)
				)
				(justify left bottom)
				(hide yes)
			)
		)
		(property "Description" ""
			(at 227.33 144.78 0)
			(effects
				(font
					(size 1.27 1.27)
				)
				(hide yes)
			)
		)
		(property "MPN" "ERJ2GE0R00X"
			(at 247.65 165.1 0)
			(effects
				(font
					(size 1.27 1.27)
					(thickness 0.15)
				)
				(justify left bottom)
				(hide yes)
			)
		)
		(property "Manufacturer" "Panasonic"
			(at 247.65 167.64 0)
			(effects
				(font
					(size 1.27 1.27)
					(thickness 0.15)
				)
				(justify left bottom)
				(hide yes)
			)
		)
		(property "License" "Apache-2.0"
			(at 247.65 170.18 0)
			(effects
				(font
					(size 1.27 1.27)
					(thickness 0.15)
				)
				(justify left bottom)
				(hide yes)
			)
		)
		(property "Author" "Antmicro"
			(at 247.65 172.72 0)
			(effects
				(font
					(size 1.27 1.27)
					(thickness 0.15)
				)
				(justify left bottom)
				(hide yes)
			)
		)
		(property "Val" "0R"
			(at 226.06 143.51 0)
			(effects
				(font
					(size 1.27 1.27)
					(thickness 0.15)
				)
			)
		)
		(property "Tolerance" "~"
			(at 247.65 154.94 0)
			(effects
				(font
					(size 1.27 1.27)
				)
				(justify left bottom)
				(hide yes)
			)
		)
		(property "Current" "1A"
			(at 247.65 175.26 0)
			(effects
				(font
					(size 1.27 1.27)
					(thickness 0.15)
				)
				(justify left bottom)
				(hide yes)
			)
		)
		(property "Public" "False"
			(at 247.65 175.26 0)
			(effects
				(font
					(size 1.27 1.27)
				)
				(justify left bottom)
				(hide yes)
			)
		)
		(pin "1"
		)
		(pin "2"
		)
		(instances
			(project "com-express-7-baseboard"
				(path ""
					(reference "R243")
					(unit 1)
				)
			)
		)
	)
	(symbol
		(lib_id "antmicroResistors0402:R_0R_0402")
		(at 180.34 176.53 90)
		(unit 1)
		(exclude_from_sim no)
		(in_bom yes)
		(on_board yes)
		(dnp no)
		(property "Reference" "R232"
			(at 181.61 172.72 90)
			(effects
				(font
					(size 1.27 1.27)
					(thickness 0.15)
				)
				(justify right)
			)
		)
		(property "Value" "R_0R_0402"
			(at 193.04 156.21 0)
			(effects
				(font
					(size 1.27 1.27)
					(thickness 0.15)
				)
				(justify left bottom)
				(hide yes)
			)
		)
		(property "Footprint" "antmicro-footprints:R_0402_1005Metric"
			(at 195.58 156.21 0)
			(effects
				(font
					(size 1.27 1.27)
					(thickness 0.15)
				)
				(justify left bottom)
				(hide yes)
			)
		)
		(property "Datasheet" "https://industrial.panasonic.com/cdbs/www-data/pdf/RDA0000/AOA0000C301.pdf"
			(at 198.12 156.21 0)
			(effects
				(font
					(size 1.27 1.27)
					(thickness 0.15)
				)
				(justify left bottom)
				(hide yes)
			)
		)
		(property "Description" ""
			(at 180.34 176.53 0)
			(effects
				(font
					(size 1.27 1.27)
				)
				(hide yes)
			)
		)
		(property "MPN" "ERJ2GE0R00X"
			(at 200.66 156.21 0)
			(effects
				(font
					(size 1.27 1.27)
					(thickness 0.15)
				)
				(justify left bottom)
				(hide yes)
			)
		)
		(property "Manufacturer" "Panasonic"
			(at 203.2 156.21 0)
			(effects
				(font
					(size 1.27 1.27)
					(thickness 0.15)
				)
				(justify left bottom)
				(hide yes)
			)
		)
		(property "License" "Apache-2.0"
			(at 205.74 156.21 0)
			(effects
				(font
					(size 1.27 1.27)
					(thickness 0.15)
				)
				(justify left bottom)
				(hide yes)
			)
		)
		(property "Author" "Antmicro"
			(at 208.28 156.21 0)
			(effects
				(font
					(size 1.27 1.27)
					(thickness 0.15)
				)
				(justify left bottom)
				(hide yes)
			)
		)
		(property "Val" "0R"
			(at 181.61 175.26 90)
			(effects
				(font
					(size 1.27 1.27)
					(thickness 0.15)
				)
				(justify right)
			)
		)
		(property "Tolerance" "~"
			(at 190.5 156.21 0)
			(effects
				(font
					(size 1.27 1.27)
				)
				(justify left bottom)
				(hide yes)
			)
		)
		(property "Current" "1A"
			(at 210.82 156.21 0)
			(effects
				(font
					(size 1.27 1.27)
					(thickness 0.15)
				)
				(justify left bottom)
				(hide yes)
			)
		)
		(property "Public" "False"
			(at 210.82 156.21 0)
			(effects
				(font
					(size 1.27 1.27)
				)
				(justify left bottom)
				(hide yes)
			)
		)
		(pin "2"
		)
		(pin "1"
		)
		(instances
			(project "com-express-7-baseboard"
				(path ""
					(reference "R232")
					(unit 1)
				)
			)
		)
	)
	(symbol
		(lib_id "antmicroResistors0402:R_0R_0402")
		(at 189.23 137.16 0)
		(unit 1)
		(exclude_from_sim no)
		(in_bom yes)
		(on_board yes)
		(dnp no)
		(property "Reference" "R233"
			(at 186.69 135.89 0)
			(effects
				(font
					(size 1.27 1.27)
					(thickness 0.15)
				)
			)
		)
		(property "Value" "R_0R_0402"
			(at 209.55 149.86 0)
			(effects
				(font
					(size 1.27 1.27)
					(thickness 0.15)
				)
				(justify left bottom)
				(hide yes)
			)
		)
		(property "Footprint" "antmicro-footprints:R_0402_1005Metric"
			(at 209.55 152.4 0)
			(effects
				(font
					(size 1.27 1.27)
					(thickness 0.15)
				)
				(justify left bottom)
				(hide yes)
			)
		)
		(property "Datasheet" "https://industrial.panasonic.com/cdbs/www-data/pdf/RDA0000/AOA0000C301.pdf"
			(at 209.55 154.94 0)
			(effects
				(font
					(size 1.27 1.27)
					(thickness 0.15)
				)
				(justify left bottom)
				(hide yes)
			)
		)
		(property "Description" ""
			(at 189.23 137.16 0)
			(effects
				(font
					(size 1.27 1.27)
				)
				(hide yes)
			)
		)
		(property "MPN" "ERJ2GE0R00X"
			(at 209.55 157.48 0)
			(effects
				(font
					(size 1.27 1.27)
					(thickness 0.15)
				)
				(justify left bottom)
				(hide yes)
			)
		)
		(property "Manufacturer" "Panasonic"
			(at 209.55 160.02 0)
			(effects
				(font
					(size 1.27 1.27)
					(thickness 0.15)
				)
				(justify left bottom)
				(hide yes)
			)
		)
		(property "License" "Apache-2.0"
			(at 209.55 162.56 0)
			(effects
				(font
					(size 1.27 1.27)
					(thickness 0.15)
				)
				(justify left bottom)
				(hide yes)
			)
		)
		(property "Author" "Antmicro"
			(at 209.55 165.1 0)
			(effects
				(font
					(size 1.27 1.27)
					(thickness 0.15)
				)
				(justify left bottom)
				(hide yes)
			)
		)
		(property "Val" "0R"
			(at 195.58 135.89 0)
			(effects
				(font
					(size 1.27 1.27)
					(thickness 0.15)
				)
			)
		)
		(property "Tolerance" "~"
			(at 209.55 147.32 0)
			(effects
				(font
					(size 1.27 1.27)
				)
				(justify left bottom)
				(hide yes)
			)
		)
		(property "Current" "1A"
			(at 209.55 167.64 0)
			(effects
				(font
					(size 1.27 1.27)
					(thickness 0.15)
				)
				(justify left bottom)
				(hide yes)
			)
		)
		(property "Public" "False"
			(at 209.55 167.64 0)
			(effects
				(font
					(size 1.27 1.27)
				)
				(justify left bottom)
				(hide yes)
			)
		)
		(pin "2"
		)
		(pin "1"
		)
		(instances
			(project "com-express-7-baseboard"
				(path ""
					(reference "R233")
					(unit 1)
				)
			)
		)
	)
	(symbol
		(lib_id "antmicropower:GND")
		(at 180.34 177.8 0)
		(unit 1)
		(exclude_from_sim no)
		(in_bom yes)
		(on_board yes)
		(dnp no)
		(property "Reference" "#PWR0323"
			(at 189.23 180.34 0)
			(effects
				(font
					(size 1.27 1.27)
					(thickness 0.15)
				)
				(justify left bottom)
				(hide yes)
			)
		)
		(property "Value" "GND"
			(at 180.34 181.61 0)
			(effects
				(font
					(size 1.27 1.27)
					(thickness 0.15)
				)
			)
		)
		(property "Footprint" ""
			(at 189.23 185.42 0)
			(effects
				(font
					(size 1.27 1.27)
					(thickness 0.15)
				)
				(justify left bottom)
				(hide yes)
			)
		)
		(property "Datasheet" ""
			(at 189.23 190.5 0)
			(effects
				(font
					(size 1.27 1.27)
					(thickness 0.15)
				)
				(justify left bottom)
				(hide yes)
			)
		)
		(property "Description" ""
			(at 180.34 177.8 0)
			(effects
				(font
					(size 1.27 1.27)
				)
				(hide yes)
			)
		)
		(property "Author" "Antmicro"
			(at 189.23 185.42 0)
			(effects
				(font
					(size 1.27 1.27)
					(thickness 0.15)
				)
				(justify left bottom)
				(hide yes)
			)
		)
		(property "License" "Apache-2.0"
			(at 189.23 187.96 0)
			(effects
				(font
					(size 1.27 1.27)
					(thickness 0.15)
				)
				(justify left bottom)
				(hide yes)
			)
		)
		(pin "1"
		)
		(instances
			(project "com-express-7-baseboard"
				(path ""
					(reference "#PWR0323")
					(unit 1)
				)
			)
		)
	)
	(symbol
		(lib_id "antmicroCapacitors0402:C_100n_0402")
		(at 189.23 128.27 270)
		(mirror x)
		(unit 1)
		(exclude_from_sim no)
		(in_bom yes)
		(on_board yes)
		(dnp no)
		(property "Reference" "C147"
			(at 186.69 124.4536 90)
			(effects
				(font
					(size 1.27 1.27)
					(thickness 0.15)
				)
				(justify right)
			)
		)
		(property "Value" "C_100n_0402"
			(at 179.07 107.95 0)
			(effects
				(font
					(size 1.27 1.27)
					(thickness 0.15)
				)
				(justify left bottom)
				(hide yes)
			)
		)
		(property "Footprint" "antmicro-footprints:C_0402_1005Metric"
			(at 176.53 107.95 0)
			(effects
				(font
					(size 1.27 1.27)
					(thickness 0.15)
				)
				(justify left bottom)
				(hide yes)
			)
		)
		(property "Datasheet" "https://www.murata.com/products/productdetail?partno=GRM155R61H104KE14%23"
			(at 173.99 107.95 0)
			(effects
				(font
					(size 1.27 1.27)
					(thickness 0.15)
				)
				(justify left bottom)
				(hide yes)
			)
		)
		(property "Description" ""
			(at 189.23 128.27 0)
			(effects
				(font
					(size 1.27 1.27)
				)
				(hide yes)
			)
		)
		(property "MPN" "GRM155R61H104KE14D"
			(at 171.45 107.95 0)
			(effects
				(font
					(size 1.27 1.27)
					(thickness 0.15)
				)
				(justify left bottom)
				(hide yes)
			)
		)
		(property "Manufacturer" "Murata"
			(at 168.91 107.95 0)
			(effects
				(font
					(size 1.27 1.27)
					(thickness 0.15)
				)
				(justify left bottom)
				(hide yes)
			)
		)
		(property "License" "Apache-2.0"
			(at 166.37 107.95 0)
			(effects
				(font
					(size 1.27 1.27)
					(thickness 0.15)
				)
				(justify left bottom)
				(hide yes)
			)
		)
		(property "Author" "Antmicro"
			(at 163.83 107.95 0)
			(effects
				(font
					(size 1.27 1.27)
					(thickness 0.15)
				)
				(justify left bottom)
				(hide yes)
			)
		)
		(property "Val" "100n"
			(at 186.69 126.9936 90)
			(effects
				(font
					(size 1.27 1.27)
					(thickness 0.15)
				)
				(justify right)
			)
		)
		(property "Voltage" "50V"
			(at 161.29 107.95 0)
			(effects
				(font
					(size 1.27 1.27)
				)
				(justify left bottom)
				(hide yes)
			)
		)
		(property "Dielectric" "X5R"
			(at 158.75 107.95 0)
			(effects
				(font
					(size 1.27 1.27)
				)
				(justify left bottom)
				(hide yes)
			)
		)
		(property "Public" "False"
			(at 156.21 107.95 0)
			(effects
				(font
					(size 1.27 1.27)
				)
				(justify left bottom)
				(hide yes)
			)
		)
		(pin "2"
		)
		(pin "1"
		)
		(instances
			(project "com-express-7-baseboard"
				(path ""
					(reference "C147")
					(unit 1)
				)
			)
		)
	)
	(symbol
		(lib_id "antmicropower:GND")
		(at 198.12 177.8 0)
		(unit 1)
		(exclude_from_sim no)
		(in_bom yes)
		(on_board yes)
		(dnp no)
		(property "Reference" "#PWR0326"
			(at 207.01 180.34 0)
			(effects
				(font
					(size 1.27 1.27)
					(thickness 0.15)
				)
				(justify left bottom)
				(hide yes)
			)
		)
		(property "Value" "GND"
			(at 198.12 181.61 0)
			(effects
				(font
					(size 1.27 1.27)
					(thickness 0.15)
				)
			)
		)
		(property "Footprint" ""
			(at 207.01 185.42 0)
			(effects
				(font
					(size 1.27 1.27)
					(thickness 0.15)
				)
				(justify left bottom)
				(hide yes)
			)
		)
		(property "Datasheet" ""
			(at 207.01 190.5 0)
			(effects
				(font
					(size 1.27 1.27)
					(thickness 0.15)
				)
				(justify left bottom)
				(hide yes)
			)
		)
		(property "Description" ""
			(at 198.12 177.8 0)
			(effects
				(font
					(size 1.27 1.27)
				)
				(hide yes)
			)
		)
		(property "Author" "Antmicro"
			(at 207.01 185.42 0)
			(effects
				(font
					(size 1.27 1.27)
					(thickness 0.15)
				)
				(justify left bottom)
				(hide yes)
			)
		)
		(property "License" "Apache-2.0"
			(at 207.01 187.96 0)
			(effects
				(font
					(size 1.27 1.27)
					(thickness 0.15)
				)
				(justify left bottom)
				(hide yes)
			)
		)
		(pin "1"
		)
		(instances
			(project "com-express-7-baseboard"
				(path ""
					(reference "#PWR0326")
					(unit 1)
				)
			)
		)
	)
	(symbol
		(lib_id "antmicropower:+3V3")
		(at 180.34 120.65 0)
		(unit 1)
		(exclude_from_sim no)
		(in_bom yes)
		(on_board yes)
		(dnp no)
		(fields_autoplaced yes)
		(property "Reference" "#PWR0322"
			(at 195.58 120.65 0)
			(effects
				(font
					(size 1.27 1.27)
					(thickness 0.15)
				)
				(justify left bottom)
				(hide yes)
			)
		)
		(property "Value" "+3V3"
			(at 180.34 115.57 0)
			(effects
				(font
					(size 1.27 1.27)
					(thickness 0.15)
				)
			)
		)
		(property "Footprint" ""
			(at 195.58 128.27 0)
			(effects
				(font
					(size 1.27 1.27)
					(thickness 0.15)
				)
				(justify left bottom)
				(hide yes)
			)
		)
		(property "Datasheet" ""
			(at 195.58 130.81 0)
			(effects
				(font
					(size 1.27 1.27)
					(thickness 0.15)
				)
				(justify left bottom)
				(hide yes)
			)
		)
		(property "Description" ""
			(at 180.34 120.65 0)
			(effects
				(font
					(size 1.27 1.27)
				)
				(hide yes)
			)
		)
		(property "Author" "Antmicro"
			(at 195.58 123.19 0)
			(effects
				(font
					(size 1.27 1.27)
					(thickness 0.15)
				)
				(justify left bottom)
				(hide yes)
			)
		)
		(property "License" "Apache-2.0"
			(at 195.58 125.73 0)
			(effects
				(font
					(size 1.27 1.27)
					(thickness 0.15)
				)
				(justify left bottom)
				(hide yes)
			)
		)
		(pin "1"
		)
		(instances
			(project "com-express-7-baseboard"
				(path ""
					(reference "#PWR0322")
					(unit 1)
				)
			)
		)
	)
)
